# BASEBOARD_FAB2 (Tioga Pass) — schematic netlist excerpt (pin names and nets, part order shuffled) for the footprints in the layout excerpt that follows; sources: Cadence DE-HDL packaged netlist, KiCad conversion of Wiwynn_Tioga_Pass_MB.brd

C3R2  CAP_A  0.1UF 16V 10% X7R  pkg 0402V  page 192 : A = P3V3_STBY ; B = GND
C5P29  CAP  100UF 4V 20% X5R  pkg 0805  page 42 : A = PVCCMCP_CPU0 ; B = GND
C3M4  CAP  0.22UF 16V 10% X7R  pkg 0402  page 105 : A = P3E_CPU0_PE1_PCH_R_RXN<12> ; B = P3E_CPU0_PE1_PCH_RXN<12>

(kicad_pcb
	(version 20260206)
	(generator "pcbnew")
	(generator_version "10.0")
	(general
		(thickness 1.6)
		(legacy_teardrops no)
	)
	(paper "A4")
	(title_block
		(title "Wiwynn_Tioga_Pass_MB.brd")
		(comment 1 "Tioga Pass / footprints 4486-4488 of 4770")
	)
	(layers
		(0 "F.Cu" signal "TOP")
		(4 "In1.Cu" signal "L2GND")
		(6 "In2.Cu" signal "L3")
		(8 "In3.Cu" signal "L4GND")
		(10 "In4.Cu" signal "L5")
		(12 "In5.Cu" signal "L6GND")
		(14 "In6.Cu" signal "L7VCC")
		(16 "In7.Cu" signal "L8VCC")
		(18 "In8.Cu" signal "L9GND")
		(20 "In9.Cu" signal "L10")
		(22 "In10.Cu" signal "L11GND")
		(24 "In11.Cu" signal "L12")
		(26 "In12.Cu" signal "L13GND")
		(2 "B.Cu" signal "BOTTOM")
		(9 "F.Adhes" user "F.Adhesive")
		(11 "B.Adhes" user "B.Adhesive")
		(13 "F.Paste" user "Package Geometry/Pastemask Top")
		(15 "B.Paste" user "Package Geometry/Pastemask Bottom")
		(5 "F.SilkS" user "Ref Des/Silkscreen Top")
		(7 "B.SilkS" user "Ref Des/Silkscreen Bottom")
		(1 "F.Mask" user "Board Geometry/Soldermask Top")
		(3 "B.Mask" user "Board Geometry/Soldermask Bottom")
		(17 "Dwgs.User" user "User.Drawings")
		(19 "Cmts.User" user "User.Comments")
		(21 "Eco1.User" user "User.Eco1")
		(23 "Eco2.User" user "User.Eco2")
		(25 "Edge.Cuts" user "Board Geometry/Outline")
		(27 "Margin" user)
		(31 "F.CrtYd" user "Package Geometry/Place Bound Top")
		(29 "B.CrtYd" user "Package Geometry/Place Bound Bottom")
		(35 "F.Fab" user "Ref Des/Assembly Top")
		(33 "B.Fab" user "Ref Des/Assembly Bottom")
	)
	(footprint ""
		(layer "B.Cu")
		(at 354.543614 -123.780042 -90)
		(property "Reference" "C3M4"
			(at 0 0 90)
			(layer "B.SilkS")
			(hide yes)
			(effects
				(font
					(size 1.27 1.27)
				)
				(justify mirror)
			)
		)
		(property "Value" ""
			(at 0 0 90)
			(layer "B.Fab")
			(effects
				(font
					(size 1.27 1.27)
				)
				(justify mirror)
			)
		)
		(duplicate_pad_numbers_are_jumpers no)
		(fp_poly
			(pts
				(xy -0.3048 -0.1016) (xy -0.3048 0.9906) (xy 0.3048 0.9906) (xy 0.3048 -0.1016)
			)
			(stroke
				(width 0)
				(type default)
			)
			(fill no)
			(layer "B.CrtYd")
		)
		(fp_line
			(start -0.3048 0.9906)
			(end -0.3048 -0.1016)
			(stroke
				(width 0.1)
				(type default)
			)
			(layer "B.Fab")
		)
		(fp_line
			(start 0.3048 0.9906)
			(end -0.3048 0.9906)
			(stroke
				(width 0.1)
				(type default)
			)
			(layer "B.Fab")
		)
		(fp_line
			(start -0.3048 -0.1016)
			(end 0.3048 -0.1016)
			(stroke
				(width 0.1)
				(type default)
			)
			(layer "B.Fab")
		)
		(fp_line
			(start 0.3048 -0.1016)
			(end 0.3048 0.9906)
			(stroke
				(width 0.1)
				(type default)
			)
			(layer "B.Fab")
		)
		(pad "1" smd rect
			(at 0 0 90)
			(size 0.508 0.508)
			(layers "B.Cu" "B.Mask" "B.Paste")
			(net "P3E_CPU0_PE1_PCH_R_RXN<12>")
		)
		(pad "2" smd rect
			(at 0 0.889 90)
			(size 0.508 0.508)
			(layers "B.Cu" "B.Mask" "B.Paste")
			(net "P3E_CPU0_PE1_PCH_RXN<12>")
		)
		(zone
			(layer "B.Cu")
			(hatch none 0.5)
			(connect_pads
				(clearance 0)
			)
			(min_thickness 0.25)
			(keepout
				(tracks not_allowed)
				(vias allowed)
				(pads allowed)
				(copperpour not_allowed)
				(footprints allowed)
			)
			(placement
				(enabled no)
				(sheetname "")
			)
			(fill
				(thermal_gap 0.5)
				(thermal_bridge_width 0.5)
				(island_removal_mode 0)
			)
			(polygon
				(pts
					(xy 353.908614 -123.526042) (xy 353.908614 -124.034042) (xy 354.289614 -124.034042) (xy 354.289614 -123.526042)
				)
			)
		)
		(zone
			(layer "B.Cu")
			(hatch none 0.5)
			(connect_pads
				(clearance 0)
			)
			(min_thickness 0.25)
			(keepout
				(tracks allowed)
				(vias not_allowed)
				(pads allowed)
				(copperpour not_allowed)
				(footprints allowed)
			)
			(placement
				(enabled no)
				(sheetname "")
			)
			(fill
				(thermal_gap 0.5)
				(thermal_bridge_width 0.5)
				(island_removal_mode 0)
			)
			(polygon
				(pts
					(xy 354.289614 -123.526042) (xy 354.289614 -124.034042) (xy 353.908614 -124.034042) (xy 353.908614 -123.526042)
				)
			)
		)
	)
	(footprint ""
		(layer "B.Cu")
		(at 273.179286 -73.51014)
		(property "Reference" "C5P29"
			(at 0 0 0)
			(layer "B.SilkS")
			(hide yes)
			(effects
				(font
					(size 1.27 1.27)
				)
				(justify mirror)
			)
		)
		(property "Value" ""
			(at 0 0 0)
			(layer "B.Fab")
			(effects
				(font
					(size 1.27 1.27)
				)
				(justify mirror)
			)
		)
		(duplicate_pad_numbers_are_jumpers no)
		(fp_poly
			(pts
				(xy 0.7239 -0.2159) (xy -0.7239 -0.2159) (xy -0.7239 1.9939) (xy 0.7239 1.9939)
			)
			(stroke
				(width 0)
				(type default)
			)
			(fill no)
			(layer "B.CrtYd")
		)
		(fp_line
			(start -0.7239 -0.2159)
			(end 0.7239 -0.2159)
			(stroke
				(width 0.1)
				(type default)
			)
			(layer "B.Fab")
		)
		(fp_line
			(start -0.7239 1.9939)
			(end -0.7239 -0.2159)
			(stroke
				(width 0.1)
				(type default)
			)
			(layer "B.Fab")
		)
		(fp_line
			(start 0.7239 -0.2159)
			(end 0.7239 1.9939)
			(stroke
				(width 0.1)
				(type default)
			)
			(layer "B.Fab")
		)
		(fp_line
			(start 0.7239 1.9939)
			(end -0.7239 1.9939)
			(stroke
				(width 0.1)
				(type default)
			)
			(layer "B.Fab")
		)
		(pad "1" smd rect
			(at 0 0 180)
			(size 1.27 1.016)
			(layers "B.Cu" "B.Mask" "B.Paste")
			(net "PVCCMCP_CPU0")
		)
		(pad "2" smd rect
			(at 0 1.778 180)
			(size 1.27 1.016)
			(layers "B.Cu" "B.Mask" "B.Paste")
			(net "GND")
		)
		(zone
			(layer "B.Cu")
			(hatch none 0.5)
			(connect_pads
				(clearance 0)
			)
			(min_thickness 0.25)
			(keepout
				(tracks not_allowed)
				(vias allowed)
				(pads allowed)
				(copperpour not_allowed)
				(footprints allowed)
			)
			(placement
				(enabled no)
				(sheetname "")
			)
			(fill
				(thermal_gap 0.5)
				(thermal_bridge_width 0.5)
				(island_removal_mode 0)
			)
			(polygon
				(pts
					(xy 273.814286 -73.00214) (xy 272.544286 -73.00214) (xy 272.544286 -72.24014) (xy 273.814286 -72.24014)
				)
			)
		)
	)
	(footprint ""
		(layer "B.Cu")
		(at 373.126 -75.5015)
		(property "Reference" "C3R2"
			(at 0 0 0)
			(layer "B.SilkS")
			(hide yes)
			(effects
				(font
					(size 1.27 1.27)
				)
				(justify mirror)
			)
		)
		(property "Value" ""
			(at 0 0 0)
			(layer "B.Fab")
			(effects
				(font
					(size 1.27 1.27)
				)
				(justify mirror)
			)
		)
		(duplicate_pad_numbers_are_jumpers no)
		(fp_rect
			(start 0.2794 0.9144)
			(end -0.2794 -0.1143)
			(stroke
				(width 0)
				(type default)
			)
			(fill no)
			(layer "B.CrtYd")
		)
		(fp_line
			(start -0.2794 -0.1143)
			(end -0.2794 0.9144)
			(stroke
				(width 0.1)
				(type default)
			)
			(layer "B.Fab")
		)
		(fp_line
			(start -0.2794 0.9144)
			(end 0.2794 0.9144)
			(stroke
				(width 0.1)
				(type default)
			)
			(layer "B.Fab")
		)
		(fp_line
			(start 0.2794 -0.1143)
			(end -0.2794 -0.1143)
			(stroke
				(width 0.1)
				(type default)
			)
			(layer "B.Fab")
		)
		(fp_line
			(start 0.2794 0.9144)
			(end 0.2794 -0.1143)
			(stroke
				(width 0.1)
				(type default)
			)
			(layer "B.Fab")
		)
		(pad "1" smd custom
			(at 0 0 270)
			(size 0.10414 0.10414)
			(layers "B.Cu" "B.Mask" "B.Paste")
			(net "P3V3_STBY")
			(options
				(clearance outline)
				(anchor circle)
			)
			(primitives
				(gr_poly
					(pts
						(xy -0.20828 -0.08636) (xy -0.20828 0.08636) (xy -0.08636 0.20828) (xy 0.086614 0.20828) (xy 0.20828 0.086614)
						(xy 0.20828 -0.08636) (xy 0.08636 -0.20828) (xy -0.08636 -0.20828)
					)
					(width 0)
					(fill yes)
				)
			)
		)
		(pad "2" smd custom
			(at 0 0.8001 270)
			(size 0.10414 0.10414)
			(layers "B.Cu" "B.Mask" "B.Paste")
			(net "GND")
			(options
				(clearance outline)
				(anchor circle)
			)
			(primitives
				(gr_poly
					(pts
						(xy -0.20828 -0.08636) (xy -0.20828 0.08636) (xy -0.08636 0.20828) (xy 0.086614 0.20828) (xy 0.20828 0.086614)
						(xy 0.20828 -0.08636) (xy 0.08636 -0.20828) (xy -0.08636 -0.20828)
					)
					(width 0)
					(fill yes)
				)
			)
		)
		(zone
			(layer "B.Cu")
			(hatch none 0.5)
			(connect_pads
				(clearance 0)
			)
			(min_thickness 0.25)
			(keepout
				(tracks not_allowed)
				(vias allowed)
				(pads allowed)
				(copperpour not_allowed)
				(footprints allowed)
			)
			(placement
				(enabled no)
				(sheetname "")
			)
			(fill
				(thermal_gap 0.5)
				(thermal_bridge_width 0.5)
				(island_removal_mode 0)
			)
			(polygon
				(pts
					(xy 373.21363 -75.29195) (xy 373.21363 -74.91095) (xy 373.03837 -74.91095) (xy 373.038116 -75.29195)
				)
			)
		)
		(zone
			(layer "B.Cu")
			(hatch none 0.5)
			(connect_pads
				(clearance 0)
			)
			(min_thickness 0.25)
			(keepout
				(tracks allowed)
				(vias not_allowed)
				(pads allowed)
				(copperpour not_allowed)
				(footprints allowed)
			)
			(placement
				(enabled no)
				(sheetname "")
			)
			(fill
				(thermal_gap 0.5)
				(thermal_bridge_width 0.5)
				(island_removal_mode 0)
			)
			(polygon
				(pts
					(xy 373.21363 -75.29195) (xy 373.21363 -74.91095) (xy 373.03837 -74.91095) (xy 373.038116 -75.29195)
				)
			)
		)
	)
)
